# T6G (Grand Teton) — schematic netlist excerpt (pin names and nets, part order shuffled) for the footprints in the layout excerpt that follows; sources: Cadence DE-HDL packaged netlist, KiCad conversion of 04192023_DAF0TMB3IC0_F0TG_MB_C_brd_V02_OCP.brd

PL8  Q_INDUCTOR4P_14  150NH IND  pkg L_TLM117513Q-151QL_11X7-5XA  page 213
  \1\  = SW_PVDDCR_CPU0_P1_SW6
  \2\  = IND_CPU0_P1_CPL0
  \3\  = IND_CPU0_P1_CPL6
  \4\  = PVDDCR_CPU0_P1

PC199  Q_CAP  10UF 6.3V 20% X6S  pkg C0402  page 207 : A = PVDD11_S3_P0_VCCS ; B = GND

(kicad_pcb
	(version 20260206)
	(generator "pcbnew")
	(generator_version "10.0")
	(general
		(thickness 1.6)
		(legacy_teardrops no)
	)
	(paper "A4")
	(title_block
		(title "04192023_DAF0TMB3IC0_F0TG_MB_C_brd_V02_OCP.brd")
		(comment 1 "Grand Teton / footprints 2798-2799 of 8354")
	)
	(layers
		(0 "F.Cu" signal "TOP")
		(4 "In1.Cu" signal "GND")
		(6 "In2.Cu" signal "IN1")
		(8 "In3.Cu" signal "GND1")
		(10 "In4.Cu" signal "IN2")
		(12 "In5.Cu" signal "GND2")
		(14 "In6.Cu" signal "IN3")
		(16 "In7.Cu" signal "GND3")
		(18 "In8.Cu" signal "VCC")
		(20 "In9.Cu" signal "VCC1")
		(22 "In10.Cu" signal "GND4")
		(24 "In11.Cu" signal "IN4")
		(26 "In12.Cu" signal "GND5")
		(28 "In13.Cu" signal "IN5")
		(30 "In14.Cu" signal "GND6")
		(32 "In15.Cu" signal "IN6")
		(34 "In16.Cu" signal "GND7")
		(2 "B.Cu" signal "BOTTOM")
		(9 "F.Adhes" user "F.Adhesive")
		(11 "B.Adhes" user "B.Adhesive")
		(13 "F.Paste" user "Package Geometry/Pastemask Top")
		(15 "B.Paste" user "Package Geometry/Pastemask Bottom")
		(5 "F.SilkS" user "Ref Des/Silkscreen Top")
		(7 "B.SilkS" user "Ref Des/Silkscreen Bottom")
		(1 "F.Mask" user "Board Geometry/Soldermask Top")
		(3 "B.Mask" user "Board Geometry/Soldermask Bottom")
		(17 "Dwgs.User" user "User.Drawings")
		(19 "Cmts.User" user "User.Comments")
		(21 "Eco1.User" user "User.Eco1")
		(23 "Eco2.User" user "User.Eco2")
		(25 "Edge.Cuts" user "Board Geometry/Outline")
		(27 "Margin" user)
		(31 "F.CrtYd" user "Package Geometry/Place Bound Top")
		(29 "B.CrtYd" user "Package Geometry/Place Bound Bottom")
		(35 "F.Fab" user "Ref Des/Assembly Top")
		(33 "B.Fab" user "Ref Des/Assembly Bottom")
	)
	(footprint ""
		(layer "F.Cu")
		(at 421.174418 -366.202214 90)
		(property "Reference" "PC199"
			(at 0 0 90)
			(layer "F.SilkS")
			(hide yes)
			(effects
				(font
					(size 1.27 1.27)
				)
			)
		)
		(property "Value" ""
			(at 0 0 90)
			(layer "F.Fab")
			(effects
				(font
					(size 1.27 1.27)
				)
			)
		)
		(duplicate_pad_numbers_are_jumpers no)
		(fp_line
			(start 0.7874 -0.4064)
			(end 0.7874 0.4064)
			(stroke
				(width 0.1524)
				(type default)
			)
			(layer "F.SilkS")
		)
		(fp_line
			(start -0.7874 -0.4064)
			(end 0.7874 -0.4064)
			(stroke
				(width 0.1524)
				(type default)
			)
			(layer "F.SilkS")
		)
		(fp_line
			(start 0.7874 0.4064)
			(end -0.7874 0.4064)
			(stroke
				(width 0.1524)
				(type default)
			)
			(layer "F.SilkS")
		)
		(fp_line
			(start -0.7874 0.4064)
			(end -0.7874 -0.4064)
			(stroke
				(width 0.1524)
				(type default)
			)
			(layer "F.SilkS")
		)
		(fp_line
			(start -0.12065 -0.305054)
			(end -0.12065 -0.2794)
			(stroke
				(width 0.1)
				(type default)
			)
			(layer "F.Fab")
		)
		(fp_line
			(start -0.67945 -0.305054)
			(end -0.12065 -0.305054)
			(stroke
				(width 0.1)
				(type default)
			)
			(layer "F.Fab")
		)
		(fp_line
			(start 0.67945 -0.3048)
			(end 0.67945 0.3048)
			(stroke
				(width 0.1)
				(type default)
			)
			(layer "F.Fab")
		)
		(fp_line
			(start 0.12065 -0.3048)
			(end 0.67945 -0.3048)
			(stroke
				(width 0.1)
				(type default)
			)
			(layer "F.Fab")
		)
		(fp_line
			(start 0.12065 -0.2794)
			(end 0.12065 -0.3048)
			(stroke
				(width 0.1)
				(type default)
			)
			(layer "F.Fab")
		)
		(fp_line
			(start -0.12065 -0.2794)
			(end 0.12065 -0.2794)
			(stroke
				(width 0.1)
				(type default)
			)
			(layer "F.Fab")
		)
		(fp_line
			(start 0.120396 0.2794)
			(end -0.12065 0.2794)
			(stroke
				(width 0.1)
				(type default)
			)
			(layer "F.Fab")
		)
		(fp_line
			(start -0.12065 0.2794)
			(end -0.12065 0.3048)
			(stroke
				(width 0.1)
				(type default)
			)
			(layer "F.Fab")
		)
		(fp_line
			(start 0.67945 0.3048)
			(end 0.120396 0.3048)
			(stroke
				(width 0.1)
				(type default)
			)
			(layer "F.Fab")
		)
		(fp_line
			(start 0.120396 0.3048)
			(end 0.120396 0.2794)
			(stroke
				(width 0.1)
				(type default)
			)
			(layer "F.Fab")
		)
		(fp_line
			(start -0.12065 0.3048)
			(end -0.67945 0.3048)
			(stroke
				(width 0.1)
				(type default)
			)
			(layer "F.Fab")
		)
		(fp_line
			(start -0.67945 0.3048)
			(end -0.67945 -0.305054)
			(stroke
				(width 0.1)
				(type default)
			)
			(layer "F.Fab")
		)
		(pad "1" smd circle
			(at -0.40005 0 90)
			(size 0 0)
			(layers "F.Cu" "F.Mask" "F.Paste")
			(net "PVDD11_S3_P0_VCCS")
		)
		(pad "2" smd circle
			(at 0.40005 0 90)
			(size 0 0)
			(layers "F.Cu" "F.Mask" "F.Paste")
			(net "GND")
		)
	)
	(footprint ""
		(layer "F.Cu")
		(at 65.529714 -178.24577 180)
		(property "Reference" "PL8"
			(at 3.654044 5.77723 90)
			(unlocked yes)
			(layer "F.SilkS")
			(effects
				(font
					(size 0.7874 0.5842)
					(thickness 0.1524)
				)
				(justify left)
			)
		)
		(property "Value" ""
			(at 0 0 180)
			(layer "F.Fab")
			(effects
				(font
					(size 1.27 1.27)
				)
			)
		)
		(duplicate_pad_numbers_are_jumpers no)
		(fp_line
			(start 3.750056 5.500116)
			(end 3.750056 -5.500116)
			(stroke
				(width 0.1524)
				(type default)
			)
			(layer "F.SilkS")
		)
		(fp_line
			(start 3.750056 -5.500116)
			(end 2.393442 -5.500116)
			(stroke
				(width 0.1524)
				(type default)
			)
			(layer "F.SilkS")
		)
		(fp_line
			(start 2.393442 5.500116)
			(end 3.750056 5.500116)
			(stroke
				(width 0.1524)
				(type default)
			)
			(layer "F.SilkS")
		)
		(fp_line
			(start -2.393442 5.500116)
			(end -3.750056 5.500116)
			(stroke
				(width 0.1524)
				(type default)
			)
			(layer "F.SilkS")
		)
		(fp_line
			(start -3.750056 5.500116)
			(end -3.750056 -5.500116)
			(stroke
				(width 0.1524)
				(type default)
			)
			(layer "F.SilkS")
		)
		(fp_line
			(start -3.750056 -5.500116)
			(end -2.393442 -5.500116)
			(stroke
				(width 0.1524)
				(type default)
			)
			(layer "F.SilkS")
		)
		(fp_poly
			(pts
				(xy -4.272534 -4.92125) (xy -5.288534 -4.41325) (xy -5.288534 -5.42925)
			)
			(stroke
				(width 0)
				(type default)
			)
			(fill yes)
			(layer "F.SilkS")
		)
		(fp_line
			(start 3.750056 5.500116)
			(end 3.750056 -5.500116)
			(stroke
				(width 0.1)
				(type default)
			)
			(layer "F.Fab")
		)
		(fp_line
			(start 3.750056 -5.500116)
			(end -3.750056 -5.500116)
			(stroke
				(width 0.1)
				(type default)
			)
			(layer "F.Fab")
		)
		(fp_line
			(start -3.750056 5.500116)
			(end 3.750056 5.500116)
			(stroke
				(width 0.1)
				(type default)
			)
			(layer "F.Fab")
		)
		(fp_line
			(start -3.750056 -5.500116)
			(end -3.750056 5.500116)
			(stroke
				(width 0.1)
				(type default)
			)
			(layer "F.Fab")
		)
		(fp_poly
			(pts
				(xy -4.9276 -4.757928) (xy -4.9276 -3.741928) (xy -3.9116 -4.249928)
			)
			(stroke
				(width 0)
				(type default)
			)
			(fill yes)
			(layer "F.Fab")
		)
		(pad "1" smd rect
			(at 0 -4.249928 90)
			(size 2.413 4.5212)
			(layers "F.Cu" "F.Mask" "F.Paste")
			(net "SW_PVDDCR_CPU0_P1_SW6")
		)
		(pad "2" smd rect
			(at 0 -1.175004 90)
			(size 1.3716 4.5212)
			(layers "F.Cu" "F.Mask" "F.Paste")
			(net "IND_CPU0_P1_CPL0")
		)
		(pad "3" smd rect
			(at 0 1.175004 90)
			(size 1.3716 4.5212)
			(layers "F.Cu" "F.Mask" "F.Paste")
			(net "IND_CPU0_P1_CPL6")
		)
		(pad "4" smd rect
			(at 0 4.249928 90)
			(size 2.413 4.5212)
			(layers "F.Cu" "F.Mask" "F.Paste")
			(net "PVDDCR_CPU0_P1")
		)
	)
)
